(kicad_pcb
	(version 20221018)
	(generator pcbnew)
	(general
    (thickness 1.562)
  )
	(paper "A4")
	(title_block
    (title "Thunderbolt PCIe Adaper")
    (date "2024-07-09")
    (rev "1.0.3")
    (comment 1 "www.antmicro.com")
    (comment 2 "Antmicro Ltd.")
		(comment 9 "footprints 44-50 of 271")
	)
	(layers
    (0 "F.Cu" signal)
    (1 "In1.Cu" signal)
    (2 "In2.Cu" signal)
    (3 "In3.Cu" signal)
    (4 "In4.Cu" signal)
    (31 "B.Cu" signal)
    (32 "B.Adhes" user "B.Adhesive")
    (33 "F.Adhes" user "F.Adhesive")
    (34 "B.Paste" user)
    (35 "F.Paste" user)
    (36 "B.SilkS" user "B.Silkscreen")
    (37 "F.SilkS" user "F.Silkscreen")
    (38 "B.Mask" user)
    (39 "F.Mask" user)
    (40 "Dwgs.User" user "User.Drawings")
    (41 "Cmts.User" user "User.Comments")
    (42 "Eco1.User" user "User.Eco1")
    (43 "Eco2.User" user "User.Eco2")
    (44 "Edge.Cuts" user)
    (45 "Margin" user)
    (46 "B.CrtYd" user "B.Courtyard")
    (47 "F.CrtYd" user "F.Courtyard")
    (48 "B.Fab" user)
    (49 "F.Fab" user)
  )
	(footprint "antmicro-footprints:MP_Pad6mm_Drill3mm" (layer "F.Cu")
    (at 166 54)
    (property "Author" "Antmicro")
    (property "License" "Apache-2.0")
    (property "Sheetfile" "connectors.kicad_sch")
    (property "Sheetname" "Connectors")
    (property "exclude_from_bom" "")
    (property "ki_description" "Mechanical part")
    (property "ki_keywords" "MECHANICAL")
    (attr exclude_from_pos_files exclude_from_bom)
    (fp_text reference "MP2" (at 0 -3.2) (layer "F.SilkS") hide
        (effects (font (size 0.7 0.7) (thickness 0.15)) (justify left bottom))
    )
    (fp_text value "MP_Pad6mm_Drill3mm" (at 0 3.9) (layer "F.Fab")
        (effects (font (size 0.7 0.7) (thickness 0.15)) (justify left bottom))
    )
    (fp_text user "License: Apache-2.0" (at -0.178 8.425) (layer "F.Fab") hide
        (effects (font (size 0.7 0.7) (thickness 0.15)) (justify left bottom))
    )
    (fp_text user "${REFERENCE}" (at -0.178 6.025) (layer "F.Fab") hide
        (effects (font (size 0.7 0.7) (thickness 0.15)) (justify left bottom))
    )
    (fp_text user "Author: Antmicro" (at -0.178 7.225) (layer "F.Fab") hide
        (effects (font (size 0.7 0.7) (thickness 0.15)) (justify left bottom))
    )
    (fp_circle (center 0 0) (end 3.25 0)
      (stroke (width 0.05) (type default)) (fill none) (layer "F.CrtYd"))
    (pad "1" thru_hole circle (at 0 0) (size 6 6) (drill 3) (layers "*.Cu" "*.Mask")
      (net 1 "GND") (pintype "passive"))
  )
	(footprint "antmicro-footprints:TP_SMD_1mm" (layer "F.Cu")
    (at 125.4 59.99)
    (property "Author" "Antmicro")
    (property "License" "Apache-2.0")
    (property "MPN" "")
    (property "Manufacturer" "")
    (property "Sheetfile" "power.kicad_sch")
    (property "Sheetname" "Power")
    (property "exclude_from_bom" "")
    (property "ki_description" "Test point 1mm SMD")
    (property "ki_keywords" "TESTPOINT")
    (attr exclude_from_pos_files exclude_from_bom)
    (fp_text reference "TP7" (at 0.584 0.462) (layer "F.SilkS")
        (effects (font (size 0.7 0.7) (thickness 0.15)) (justify left bottom))
    )
    (fp_text value "TP_1mm_SMD" (at 0 1.4) (layer "F.Fab")
        (effects (font (size 0.7 0.7) (thickness 0.15)) (justify left bottom))
    )
    (fp_text user "Author: Antmicro" (at -0.5 4) (layer "F.Fab") hide
        (effects (font (size 0.7 0.7) (thickness 0.15)) (justify left bottom))
    )
    (fp_text user "License: Apache-2.0" (at -0.5 5.2) (layer "F.Fab") hide
        (effects (font (size 0.7 0.7) (thickness 0.15)) (justify left bottom))
    )
    (fp_text user "${REFERENCE}" (at -0.5 2.8) (layer "F.Fab") hide
        (effects (font (size 0.7 0.7) (thickness 0.15)) (justify left bottom))
    )
    (fp_circle (center 0 0) (end 0.6 0)
      (stroke (width 0.05) (type default)) (fill none) (layer "F.CrtYd"))
    (pad "1" smd circle (at 0 0) (size 1 1) (layers "F.Cu" "F.Mask")
      (net 100 "Net-(D2-A)") (pinfunction "1") (pintype "passive"))
  )
	(footprint "antmicro-footprints:L_Coilcraft-XAL7070" (layer "F.Cu")
    (at 110.325 72.8)
    (property "Author" "Antmicro")
    (property "IMax" "9.2 A")
    (property "ISat" "12.8 A")
    (property "License" "Apache-2.0")
    (property "MPN" "XAL7070-682MEC")
    (property "Manufacturer" "Coilcraft")
    (property "Sheetfile" "power.kicad_sch")
    (property "Sheetname" "Power")
    (property "Size" "7.7x8")
    (property "Val" "6u8/12.8A")
    (property "ki_description" "Power Inductor (SMT), 6.8 µH, 9.2 A, Shielded, 12.8 A, XAL7070")
    (property "ki_keywords" "SMT, INDUCTOR, PASSIVE")
    (attr smd)
    (fp_text reference "L1" (at -4.026 -4.474) (layer "F.SilkS")
        (effects (font (size 0.7 0.7) (thickness 0.15)) (justify left bottom))
    )
    (fp_text value "L_6u8_12.8A_Coilcraft-XAL7070" (at 0 5.2) (layer "F.Fab")
        (effects (font (size 0.7 0.7) (thickness 0.15)) (justify left bottom))
    )
    (fp_text user "Author: Antmicro" (at -4.09 7.2) (layer "F.Fab") hide
        (effects (font (size 0.7 0.7) (thickness 0.15)) (justify left bottom))
    )
    (fp_text user "${REFERENCE}" (at -4.09 8.4) (layer "F.Fab") hide
        (effects (font (size 0.7 0.7) (thickness 0.15)) (justify left bottom))
    )
    (fp_text user "License: Apache-2.0" (at -4.09 9.6) (layer "F.Fab") hide
        (effects (font (size 0.7 0.7) (thickness 0.15)) (justify left bottom))
    )
    (fp_line (start -3.85 4) (end -3.85 -4)
      (stroke (width 0.15) (type solid)) (layer "F.SilkS"))
    (fp_line (start -3.85 4) (end 3.85 4)
      (stroke (width 0.15) (type solid)) (layer "F.SilkS"))
    (fp_line (start 3.85 -4) (end -3.85 -4)
      (stroke (width 0.15) (type solid)) (layer "F.SilkS"))
    (fp_line (start 3.85 -4) (end 3.85 4)
      (stroke (width 0.15) (type solid)) (layer "F.SilkS"))
    (fp_rect (start -4.09 -4.25) (end 4.09 4.25)
      (stroke (width 0.05) (type solid)) (fill none) (layer "F.CrtYd"))
    (fp_line (start -3.85 -4) (end 3.85 -4)
      (stroke (width 0.15) (type solid)) (layer "F.Fab"))
    (fp_line (start -3.85 4) (end -3.85 -4)
      (stroke (width 0.15) (type solid)) (layer "F.Fab"))
    (fp_line (start 3.85 -4) (end 3.85 4)
      (stroke (width 0.15) (type solid)) (layer "F.Fab"))
    (fp_line (start 3.85 4) (end -3.85 4)
      (stroke (width 0.15) (type solid)) (layer "F.Fab"))
    (pad "1" smd roundrect (at -2.41 0) (size 1.92 6.5) (layers "F.Cu" "F.Paste" "F.Mask") (roundrect_rratio 0.1)
      (net 4 "Net-(C26-Pad2)") (pintype "passive"))
    (pad "2" smd roundrect (at 2.41 0) (size 1.92 6.5) (layers "F.Cu" "F.Paste" "F.Mask") (roundrect_rratio 0.1)
      (net 268 "Net-(C28-Pad2)") (pintype "passive"))
  )
	(footprint "antmicro-footprints:TP_SMD_1mm" (layer "F.Cu")
    (at 108.425 86.4)
    (property "Author" "Antmicro")
    (property "License" "Apache-2.0")
    (property "MPN" "")
    (property "Manufacturer" "")
    (property "Sheetfile" "power.kicad_sch")
    (property "Sheetname" "Power")
    (property "exclude_from_bom" "")
    (property "ki_description" "Test point 1mm SMD")
    (property "ki_keywords" "TESTPOINT")
    (attr exclude_from_pos_files exclude_from_bom)
    (fp_text reference "TP5" (at -4.666 -0.294) (layer "F.SilkS")
        (effects (font (size 0.7 0.7) (thickness 0.15)) (justify left bottom))
    )
    (fp_text value "TP_1mm_SMD" (at 0 1.4) (layer "F.Fab")
        (effects (font (size 0.7 0.7) (thickness 0.15)) (justify left bottom))
    )
    (fp_text user "${REFERENCE}" (at -0.5 2.8) (layer "F.Fab") hide
        (effects (font (size 0.7 0.7) (thickness 0.15)) (justify left bottom))
    )
    (fp_text user "Author: Antmicro" (at -0.5 4) (layer "F.Fab") hide
        (effects (font (size 0.7 0.7) (thickness 0.15)) (justify left bottom))
    )
    (fp_text user "License: Apache-2.0" (at -0.5 5.2) (layer "F.Fab") hide
        (effects (font (size 0.7 0.7) (thickness 0.15)) (justify left bottom))
    )
    (fp_circle (center 0 0) (end 0.6 0)
      (stroke (width 0.05) (type default)) (fill none) (layer "F.CrtYd"))
    (pad "1" smd circle (at 0 0) (size 1 1) (layers "F.Cu" "F.Mask")
      (net 206 "Net-(U1-ISMON)") (pinfunction "1") (pintype "passive"))
  )
	(footprint "antmicro-footprints:C_0603_1608Metric" (layer "F.Cu")
    (at 117.98 59.11)
    (descr "Capacitor SMD 0603")
    (tags "capacitor 0603")
    (property "Author" "Antmicro")
    (property "Dielectric" "")
    (property "License" "Apache-2.0")
    (property "MPN" "GRM188R60J226MEA0D")
    (property "Manufacturer" "Murata")
    (property "Sheetfile" "power.kicad_sch")
    (property "Sheetname" "Power")
    (property "Val" "22u")
    (property "Voltage" "")
    (property "ki_description" "SMD Multilayer Ceramic Capacitor, 22 µF, 6.3 V, 0603 [1608 Metric], ± 20%, X5R, GRM Series")
    (property "ki_keywords" "0603, SMT, CAPACITOR, PASSIVE, CERAMIC, MLCC")
    (attr smd)
    (fp_text reference "C44" (at -3.426 0.479) (layer "F.SilkS")
        (effects (font (size 0.7 0.7) (thickness 0.15)) (justify left bottom))
    )
    (fp_text value "C_22u_0603" (at -1.42757 1.770288) (layer "F.Fab")
        (effects (font (size 0.7 0.7) (thickness 0.15)) (justify left bottom))
    )
    (fp_text user "Author: Antmicro" (at -1.682 4.894) (layer "F.Fab") hide
        (effects (font (size 0.7 0.7) (thickness 0.15)) (justify left bottom))
    )
    (fp_text user "${REFERENCE}" (at -1.682 3.895) (layer "F.Fab") hide
        (effects (font (size 0.7 0.7) (thickness 0.15)) (justify left bottom))
    )
    (fp_text user "License: Apache-2.0" (at -1.682 5.895) (layer "F.Fab") hide
        (effects (font (size 0.7 0.7) (thickness 0.15)) (justify left bottom))
    )
    (fp_line (start -0.15 -0.4) (end 0.15 -0.4)
      (stroke (width 0.15) (type solid)) (layer "F.SilkS"))
    (fp_line (start -0.15 0.4) (end 0.15 0.4)
      (stroke (width 0.15) (type solid)) (layer "F.SilkS"))
    (fp_rect (start -1.25 -0.65) (end 1.25 0.65)
      (stroke (width 0.05) (type solid)) (fill none) (layer "F.CrtYd"))
    (fp_rect (start -0.8 -0.4) (end 0.8 0.4)
      (stroke (width 0.15) (type solid)) (fill none) (layer "F.Fab"))
    (pad "1" smd roundrect (at -0.7 0) (size 0.8 1) (layers "F.Cu" "F.Paste" "F.Mask") (roundrect_rratio 0.2)
      (net 1 "GND") (pintype "passive"))
    (pad "2" smd roundrect (at 0.7 0) (size 0.8 1) (layers "F.Cu" "F.Paste" "F.Mask") (roundrect_rratio 0.2)
      (net 100 "Net-(D2-A)") (pintype "passive"))
  )
	(footprint "antmicro-footprints:QFN-11_2x2mm_P0.5mm" (layer "F.Cu")
    (at 116.411001 64.686)
    (property "Author" "Antmicro")
    (property "License" "Apache-2.0")
    (property "MPN" "MP2386GG-P")
    (property "Manufacturer" "Monolithic Power Systems")
    (property "Sheetfile" "power.kicad_sch")
    (property "Sheetname" "Power")
    (property "ki_description" "DC/DC converter")
    (property "ki_keywords" "IC")
    (attr smd)
    (fp_text reference "U2" (at -0.587001 2.497 unlocked) (layer "F.SilkS")
        (effects (font (size 0.7 0.7) (thickness 0.15)) (justify left bottom))
    )
    (fp_text value "MP2386GG" (at -1.637158 2.644508 unlocked) (layer "F.Fab")
        (effects (font (size 0.7 0.7) (thickness 0.15)) (justify left bottom))
    )
    (fp_text user "License: Apache-2.0" (at -1.401 5.85) (layer "F.Fab") hide
        (effects (font (size 0.7 0.7) (thickness 0.15)) (justify left bottom))
    )
    (fp_text user "Author: Antmicro" (at -1.401 4.65) (layer "F.Fab") hide
        (effects (font (size 0.7 0.7) (thickness 0.15)) (justify left bottom))
    )
    (fp_text user "${REFERENCE}" (at -1.401 3.45) (layer "F.Fab") hide
        (effects (font (size 0.7 0.7) (thickness 0.15)) (justify left bottom))
    )
    (fp_line (start -1.25 -0.951) (end -1.25 -1.25)
      (stroke (width 0.15) (type solid)) (layer "F.SilkS"))
    (fp_line (start -1.25 1.249) (end -1.25 0.949)
      (stroke (width 0.15) (type solid)) (layer "F.SilkS"))
    (fp_line (start -0.951 1.249) (end -1.25 1.249)
      (stroke (width 0.15) (type solid)) (layer "F.SilkS"))
    (fp_line (start 0.949 -1.25) (end 1.249 -1.25)
      (stroke (width 0.15) (type solid)) (layer "F.SilkS"))
    (fp_line (start 1.249 -1.25) (end 1.249 -0.951)
      (stroke (width 0.15) (type solid)) (layer "F.SilkS"))
    (fp_line (start 1.249 0.949) (end 1.249 1.249)
      (stroke (width 0.15) (type solid)) (layer "F.SilkS"))
    (fp_line (start 1.249 1.249) (end 0.949 1.249)
      (stroke (width 0.15) (type solid)) (layer "F.SilkS"))
    (fp_circle (center -1.7 -1.1) (end -1.649 -1.1)
      (stroke (width 0.15) (type solid)) (fill solid) (layer "F.SilkS"))
    (fp_rect (start -1.5 -1.5) (end 1.498 1.498)
      (stroke (width 0.05) (type solid)) (fill none) (layer "F.CrtYd"))
    (fp_line (start -1.101 1.1) (end -1.101 -0.552)
      (stroke (width 0.15) (type solid)) (layer "F.Fab"))
    (fp_line (start -0.552 -1.101) (end -1.101 -0.552)
      (stroke (width 0.15) (type solid)) (layer "F.Fab"))
    (fp_line (start -0.552 -1.101) (end 1.1 -1.101)
      (stroke (width 0.15) (type solid)) (layer "F.Fab"))
    (fp_line (start 1.1 -1.101) (end 1.1 1.1)
      (stroke (width 0.15) (type solid)) (layer "F.Fab"))
    (fp_line (start 1.1 1.1) (end -1.101 1.1)
      (stroke (width 0.15) (type solid)) (layer "F.Fab"))
    (pad "1" smd roundrect (at -0.552 -0.25 180) (size 1.5 0.25) (layers "F.Cu" "F.Paste" "F.Mask") (roundrect_rratio 0.25)
      (net 90 "Net-(U2-VIN)") (pinfunction "VIN") (pintype "power_in"))
    (pad "2" smd roundrect (at -0.75 0.998 90) (size 0.7 0.25) (layers "F.Cu" "F.Paste" "F.Mask") (roundrect_rratio 0.25)
      (net 1 "GND") (pinfunction "PGND") (pintype "power_in"))
    (pad "3" smd roundrect (at -0.25 0.998 90) (size 0.7 0.25) (layers "F.Cu" "F.Paste" "F.Mask") (roundrect_rratio 0.25)
      (net 1 "GND") (pinfunction "PGND") (pintype "passive"))
    (pad "4" smd roundrect (at 0.248 0.998 90) (size 0.7 0.25) (layers "F.Cu" "F.Paste" "F.Mask") (roundrect_rratio 0.25)
      (net 1 "GND") (pinfunction "PGND") (pintype "passive"))
    (pad "5" smd roundrect (at 0.748 0.998 90) (size 0.7 0.25) (layers "F.Cu" "F.Paste" "F.Mask") (roundrect_rratio 0.25)
      (net 158 "Net-(U2-PG)") (pinfunction "PG") (pintype "open_collector"))
    (pad "6" smd roundrect (at 0.55 0.2 180) (size 1.5 0.25) (layers "F.Cu" "F.Paste" "F.Mask") (roundrect_rratio 0.25)
      (net 95 "Net-(U2-SW)") (pinfunction "SW") (pintype "power_out"))
    (pad "7" smd roundrect (at 0.949 -0.25 180) (size 0.7 0.25) (layers "F.Cu" "F.Paste" "F.Mask") (roundrect_rratio 0.25)
      (net 94 "Net-(U2-BST)") (pinfunction "BST") (pintype "input"))
    (pad "8" smd roundrect (at 0.748 -1 90) (size 0.7 0.25) (layers "F.Cu" "F.Paste" "F.Mask") (roundrect_rratio 0.25)
      (net 6 "/Power/SMPS_LDO") (pinfunction "VCC") (pintype "power_out"))
    (pad "9" smd roundrect (at 0.248 -1 90) (size 0.7 0.25) (layers "F.Cu" "F.Paste" "F.Mask") (roundrect_rratio 0.25)
      (net 1 "GND") (pinfunction "AGND") (pintype "power_in"))
    (pad "10" smd roundrect (at -0.25 -1 90) (size 0.7 0.25) (layers "F.Cu" "F.Paste" "F.Mask") (roundrect_rratio 0.25)
      (net 99 "Net-(U2-FB)") (pinfunction "FB") (pintype "input"))
    (pad "11" smd roundrect (at -0.75 -1 90) (size 0.7 0.25) (layers "F.Cu" "F.Paste" "F.Mask") (roundrect_rratio 0.25)
      (net 119 "Net-(D1-C)") (pinfunction "EN") (pintype "input"))
  )
	(footprint "antmicro-footprints:C_0805_2012Metric" (layer "F.Cu")
    (at 105.015 78.0825 -90)
    (descr "Capacitor SMD 0805")
    (tags "capacitor SMD 0805")
    (property "Author" "Antmicro")
    (property "Dielectric" "")
    (property "License" "Apache-2.0")
    (property "MPN" "GRM21BR6YA106KE43L")
    (property "Manufacturer" "Murata")
    (property "Sheetfile" "power.kicad_sch")
    (property "Sheetname" "Power")
    (property "Val" "10u")
    (property "Voltage" "35V")
    (property "ki_description" "SMD Multilayer Ceramic Capacitor, 10 µF, 35 V, 0805 [2012 Metric], ± 10%, X5R, GRM Series")
    (property "ki_keywords" "0805, SMT, CAPACITOR, PASSIVE")
    (attr smd)
    (fp_text reference "C11" (at 1.0385 -1.919 -90) (layer "F.SilkS")
        (effects (font (size 0.7 0.7) (thickness 0.15)) (justify left bottom))
    )
    (fp_text value "C_10u_0805_35V" (at -2.055717 1.963152 -90) (layer "F.Fab")
        (effects (font (size 0.7 0.7) (thickness 0.15)) (justify left bottom))
    )
    (fp_text user "License: Apache-2.0" (at -1.9 4.947 -90) (layer "F.Fab") hide
        (effects (font (size 0.7 0.7) (thickness 0.15)) (justify left bottom))
    )
    (fp_text user "${REFERENCE}" (at -1.9 3.947 -90) (layer "F.Fab") hide
        (effects (font (size 0.7 0.7) (thickness 0.15)) (justify left bottom))
    )
    (fp_text user "Author: Antmicro" (at -1.9 5.947 -90) (layer "F.Fab") hide
        (effects (font (size 0.7 0.7) (thickness 0.15)) (justify left bottom))
    )
    (fp_line (start -0.3 -0.7) (end 0.3 -0.7)
      (stroke (width 0.15) (type solid)) (layer "F.SilkS"))
    (fp_line (start -0.3 0.7) (end 0.3 0.7)
      (stroke (width 0.15) (type solid)) (layer "F.SilkS"))
    (fp_rect (start 1.95 -0.9) (end -1.95 0.9)
      (stroke (width 0.05) (type default)) (fill none) (layer "F.CrtYd"))
    (fp_rect (start -0.95 -0.675) (end 0.95 0.675)
      (stroke (width 0.15) (type solid)) (fill none) (layer "F.Fab"))
    (pad "1" smd roundrect (at -1.1 0 270) (size 1.2 1.3) (layers "F.Cu" "F.Paste" "F.Mask") (roundrect_rratio 0.25)
      (net 1 "GND") (pintype "passive"))
    (pad "2" smd roundrect (at 1.1 0 270) (size 1.2 1.3) (layers "F.Cu" "F.Paste" "F.Mask") (roundrect_rratio 0.25)
      (net 74 "Net-(C10-Pad2)") (pintype "passive"))
  )
)
